G04 ================== begin FILE IDENTIFICATION RECORD ==================*
G04 Layout Name:  15968-1a.brd*
G04 Film Name:    DP_REF_L4*
G04 File Format:  Gerber RS274X*
G04 File Origin:  Cadence Allegro 16.5-S058*
G04 Origin Date:  Fri Oct 14 10:23:52 2016*
G04 *
G04 Layer:  BOARD GEOMETRY/DP_REF_L4_TBL*
G04 Layer:  BOARD GEOMETRY/DP_REF_L4_L4*
G04 Layer:  BOARD GEOMETRY/PANEL_OUTLINE*
G04 *
G04 Offset:    (0.00 0.00)*
G04 Mirror:    No*
G04 Mode:      Positive*
G04 Rotation:  0*
G04 FullContactRelief:  No*
G04 UndefLineWidth:     6.00*
G04 ================== end FILE IDENTIFICATION RECORD ====================*
%FSLAX35Y35*MOIN*%
%IR0*IPPOS*OFA0.00000B0.00000*MIA0B0*SFA1.00000B1.00000*%
%ADD10C,.02*%
%ADD11C,.005*%
%ADD12C,.006*%
G75*
%LPD*%
G75*
G54D10*
G01X687653Y496146D02*
X1212653D01*
G01X687653Y461496D02*
X1212653D01*
G01X687653Y426846D02*
X1212653D01*
G01X687653Y530796D02*
Y426846D01*
G01Y530796D02*
X1212653D01*
G01X862653D02*
Y426846D01*
G01X1107653Y530796D02*
Y426846D01*
G01X1212653Y530796D02*
Y426846D01*
G54D11*
G01X-21653Y-58346D02*
G03X-6653Y-73346I15000J0D01*
G01X65080D02*
X-6653D01*
G01X9506Y0D02*
X69017D01*
G01X6722Y1153D02*
G03X9506Y0I2784J2784D01*
G01X1154Y6721D02*
X6722Y1153D01*
G01X1Y9505D02*
G03X1154Y6721I3937J0D01*
G01X1Y238051D02*
Y9505D01*
G01Y238051D02*
Y9505D01*
G01X-21653Y238051D02*
Y9505D01*
G01X1D02*
G03X1154Y6721I3937J0D01*
G01X-7873Y9505D02*
G03X-4414Y1153I11811J-1D01*
G01X1154Y6721D02*
X6722Y1153D01*
G01X-4414D02*
X1154Y-4415D01*
G01X6722Y1153D02*
G03X9506Y0I2784J2784D01*
G01X1154Y-4415D02*
G03X9506Y-7874I8351J8352D01*
G01Y0D02*
X69017D01*
G01X9506Y-7874D02*
X14917D01*
G01X-21653Y9505D02*
Y-58346D01*
G01X14917Y-7874D02*
G03Y0I0J3937D01*
G01X-7873Y50852D02*
Y9505D01*
G01Y81561D02*
G03X1I3937J-1D01*
G01Y50852D02*
G03X-7873I-3937J0D01*
G01Y186482D02*
Y81561D01*
G01X13443Y249862D02*
X611812D01*
G01X10659Y251015D02*
G03X13443Y249862I2784J2784D01*
G01X1154Y260520D02*
X10659Y251015D01*
G01X3938Y241988D02*
G03X1Y238051I0J-3937D01*
G01X602307Y241988D02*
X3938D01*
G01X602307D02*
X3938D01*
G01D02*
G03X1Y238051I0J-3937D01*
G01X-7873D02*
Y217191D01*
G01X1154Y260520D02*
X10659Y251015D01*
G01D02*
G03X13443Y249862I2784J2784D01*
G01D02*
X611812D01*
G01X-21653Y238051D02*
Y534327D01*
G01X-7873Y238051D02*
Y263304D01*
G01Y217191D02*
G03X1I3937J-1D01*
G01Y186482D02*
G03X-7873I-3937J0D01*
G01X1Y263304D02*
G03X1154Y260520I3937J0D01*
G01X1Y328602D02*
Y263304D01*
G01X3938Y332539D02*
G03X1Y328602I0J-3937D01*
G01X53151Y332539D02*
X3938D01*
G01X53151D02*
X3938D01*
G01D02*
G03X1Y328602I0J-3937D01*
G01X3938Y340413D02*
G03X-7873Y328602I0J-11811D01*
G01X1D02*
Y263304D01*
G01X-7873Y328602D02*
Y263304D01*
G01X1D02*
G03X1154Y260520I3937J0D01*
G01X10965Y332539D02*
G03Y340413I0J3937D01*
G01D02*
X3938D01*
G01X-6653Y565196D02*
G03X-21653Y550196I0J-15000D01*
G01X67796Y565196D02*
X-6653D01*
G01X-21653Y542201D02*
Y550196D01*
G01Y534327D02*
G03Y542201I0J3937D01*
G01X74922Y-73346D02*
X175828D01*
G01X72954Y-71378D02*
X74922Y-73346D01*
G01X72954Y-3937D02*
Y-71378D01*
G01X65080Y-7874D02*
Y-71772D01*
G01D02*
Y-73346D01*
G01X72954Y-3937D02*
G03X69017Y0I-3937J0D01*
G01X72954Y-3937D02*
G03X69017Y0I-3937J0D01*
G01X45626D02*
G03Y-7874I0J-3937D01*
G01D02*
X65080D01*
G01X51397Y241988D02*
G03Y249862I0J3937D01*
G01X93906D02*
G03Y241988I0J-3937D01*
G01X53151Y332539D02*
G03X57088Y336476I0J3937D01*
G01Y482345D02*
Y336476D01*
G01Y482345D02*
Y336476D01*
G01X53151Y332539D02*
G03X57088Y336476I0J3937D01*
G01X41674Y340413D02*
G03Y332539I0J-3937D01*
G01X49214Y340413D02*
X41674D01*
G01X49214Y442487D02*
Y340413D01*
G01X67796Y565196D02*
Y499724D01*
G01X75670Y563228D02*
Y495787D01*
G01X58241Y485129D02*
G03X57088Y482345I2784J-2784D01*
G01X63808Y490697D02*
X58241Y485129D01*
G01X66592Y491850D02*
G03X63808Y490697I0J-3937D01*
G01X71733Y491850D02*
X66592D01*
G01X71733D02*
G03X75670Y495787I0J3937D01*
G01X67796Y499724D02*
X66592D01*
G01Y491850D02*
G03X63808Y490697I0J-3937D01*
G01X66592Y499724D02*
G03X58240Y496265I-1J-11811D01*
G01X63808Y490697D02*
X58241Y485129D01*
G01X58240Y496264D02*
X52673Y490696D01*
G01X58241Y485129D02*
G03X57088Y482345I2784J-2784D01*
G01X52673Y490697D02*
G03X49214Y482343I8352J-8351D01*
G01Y482345D02*
Y473195D01*
G01X57088Y442487D02*
G03X49214I-3937J-1D01*
G01Y473195D02*
G03X57088I3937J0D01*
G01X77639Y565196D02*
X75670Y563228D01*
G01X173111Y565196D02*
X77639D01*
G01X177796Y-71378D02*
Y-52874D01*
G01X175828Y-73346D02*
X177796Y-71378D01*
G01X187245Y-52874D02*
G03X177796I-4725J0D01*
G01X175080Y563228D02*
X173111Y565196D01*
G01X175080Y534488D02*
Y563228D01*
G01Y534488D02*
G03X175867Y533700I787J-1D01*
G01X209529D02*
X175867D01*
G01X189214Y-73346D02*
X403466D01*
G01X187245Y-71378D02*
X189214Y-73346D01*
G01X187245Y-52874D02*
Y-71378D01*
G01X261956Y167100D02*
X454172D01*
G01X262536Y165700D02*
X264036D01*
G01X257611Y162755D02*
X261956Y167100D01*
G01X258768Y161932D02*
X262536Y165700D01*
G01X255737Y158895D02*
X257611Y162755D01*
G01X257115Y158527D02*
X258768Y161932D01*
G01X255718Y158624D02*
X255737Y158895D01*
G01X256888Y155271D02*
X257115Y158527D01*
G01X255500Y155500D02*
X255717Y158624D01*
G01X256888Y155271D02*
X257115Y158527D01*
G01X254873Y153119D02*
X255500Y155500D01*
G01X256318Y153104D02*
X256888Y155271D01*
G01X256066Y152148D02*
X256318Y153104D01*
G01X254428Y152897D02*
X254873Y153119D01*
G01X255499Y151866D02*
X256066Y152148D01*
G01X255053Y151643D02*
X255499Y151866D01*
G01X261956Y167100D02*
X454172D01*
G01X261956D02*
X454172D01*
G01X261956D02*
X454172D01*
G01X261956D02*
X454172D01*
G01X261956D02*
X454172D01*
G01X261956D02*
X454172D01*
G01X261956D02*
X454172D01*
G01X261956D02*
X454172D01*
G01X261956D02*
X454172D01*
G01X261956D02*
X454172D01*
G01X261956D02*
X454172D01*
G01X262536Y165700D02*
X264036D01*
G01X261956Y167100D02*
X454172D01*
G01X258768Y161932D02*
X262536Y165700D01*
G01X257611Y162755D02*
X261956Y167100D01*
G01X257115Y158527D02*
X258768Y161932D01*
G01X255737Y158895D02*
X257611Y162755D01*
G01X256888Y155271D02*
X257115Y158527D01*
G01X255718Y158624D02*
X255737Y158895D01*
G01X255500Y155500D02*
X255717Y158624D01*
G01X256318Y153104D02*
X256888Y155271D01*
G01X254873Y153119D02*
X255500Y155500D01*
G01X256066Y152148D02*
X256318Y153104D01*
G01X254873Y153119D02*
X255500Y155500D01*
G01X255499Y151866D02*
X256066Y152148D01*
G01X254428Y152897D02*
X254873Y153119D01*
G01X255053Y151643D02*
X255499Y151866D01*
G01X254428Y152897D02*
X254873Y153119D01*
G01X252880Y232126D02*
X253528Y232450D01*
G01X253928Y231084D02*
X254153Y231196D01*
G01X253709Y230975D02*
X253928Y231084D01*
G01X251668Y230914D02*
X252880Y232126D01*
G01X253068Y230334D02*
X253709Y230975D01*
G01X251668Y224152D02*
Y230914D01*
G01X253068Y224732D02*
Y230334D01*
G01X253320Y222500D02*
X251668Y224152D01*
G01X253900Y223900D02*
X253068Y224732D01*
G01X445900Y222500D02*
X253320D01*
G01X446480Y223900D02*
X253900D01*
G01X253928Y231084D02*
X254153Y231196D01*
G01X252880Y232126D02*
X253528Y232450D01*
G01X253709Y230975D02*
X253928Y231084D01*
G01X252880Y232126D02*
X253528Y232450D01*
G01X253068Y230334D02*
X253709Y230975D01*
G01X251668Y230914D02*
X252880Y232126D01*
G01X253068Y224732D02*
Y230334D01*
G01X251668Y224152D02*
Y230914D01*
G01X253900Y223900D02*
X253068Y224732D01*
G01X253320Y222500D02*
X251668Y224152D01*
G01X446480Y223900D02*
X253900D01*
G01X445900Y222500D02*
X253320D01*
G01X209529Y533700D02*
G03X210316Y534488I0J787D01*
G01Y563228D02*
Y534488D01*
G01X212284Y565196D02*
X210316Y563228D01*
G01X426536Y565196D02*
X212284D01*
G01X342556Y165700D02*
X362556D01*
G01X337776D02*
X339276D01*
G01X332996D02*
X334496D01*
G01X309716D02*
X329716D01*
G01X304936D02*
X306436D01*
G01X300156D02*
X301656D01*
G01X276876D02*
X296876D01*
G01X272096D02*
X273596D01*
G01X267316D02*
X268816D01*
G01X342556D02*
X362556D01*
G01X337776D02*
X339276D01*
G01X332996D02*
X334496D01*
G01X309716D02*
X329716D01*
G01X304936D02*
X306436D01*
G01X300156D02*
X301656D01*
G01X276876D02*
X296876D01*
G01X272096D02*
X273596D01*
G01X267316D02*
X268816D01*
G01X405434Y-71378D02*
Y-42638D01*
G01X403466Y-73346D02*
X405434Y-71378D01*
G01X406221Y-41850D02*
X439883D01*
G01X406221D02*
G03X405434Y-42638I1J-788D01*
G01X370616Y165700D02*
X453592D01*
G01X365836D02*
X367336D01*
G01X370616D02*
X453592D01*
G01X365836D02*
X367336D01*
G01X428505Y563228D02*
X426536Y565196D01*
G01X442639Y-73346D02*
X538111D01*
G01X440670Y-71378D02*
X442639Y-73346D01*
G01X440670Y-42638D02*
Y-71378D01*
G01Y-42638D02*
G03X439883Y-41850I-787J1D01*
G01X471700Y97000D02*
Y196700D01*
G01X473100Y96420D02*
Y197280D01*
G01X465365Y90665D02*
X471700Y97000D01*
G01X465945Y89265D02*
X473100Y96420D01*
G01X452435Y90665D02*
X465365D01*
G01X461996Y89265D02*
X465945D01*
G01X457216D02*
X458716D01*
G01X452436D02*
X453936D01*
G01X473100Y96420D02*
Y197280D01*
G01X471700Y97000D02*
Y196700D01*
G01X465945Y89265D02*
X473100Y96420D01*
G01X465365Y90665D02*
X471700Y97000D01*
G01X461996Y89265D02*
X465945D01*
G01X452435Y90665D02*
X465365D01*
G01X457216Y89265D02*
X458716D01*
G01X452435Y90665D02*
X465365D01*
G01X452436Y89265D02*
X453936D01*
G01X452435Y90665D02*
X465365D01*
G01X454900Y102820D02*
Y103987D01*
G01X456300Y103400D02*
Y104206D01*
G01X456720Y101000D02*
X454900Y102820D01*
G01X457300Y102400D02*
X456300Y103400D01*
G01X460500Y101000D02*
X456720D01*
G01X459920Y102400D02*
X457300D01*
G01X464300Y104800D02*
X460500Y101000D01*
G01X462900Y105380D02*
X459920Y102400D01*
G01X464300Y156972D02*
Y104800D01*
G01X462900Y156392D02*
Y105380D01*
G01X454172Y167100D02*
X464300Y156972D01*
G01X453592Y165700D02*
X462900Y156392D01*
G01X456300Y103400D02*
Y104206D01*
G01X454900Y102820D02*
Y103987D01*
G01X457300Y102400D02*
X456300Y103400D01*
G01X456720Y101000D02*
X454900Y102820D01*
G01X459920Y102400D02*
X457300D01*
G01X460500Y101000D02*
X456720D01*
G01X462900Y105380D02*
X459920Y102400D01*
G01X464300Y104800D02*
X460500Y101000D01*
G01X462900Y156392D02*
Y105380D01*
G01X464300Y156972D02*
Y104800D01*
G01X453592Y165700D02*
X462900Y156392D01*
G01X454172Y167100D02*
X464300Y156972D01*
G01X471700Y196700D02*
X445900Y222500D01*
G01X473100Y197280D02*
X446480Y223900D01*
G01X473100Y197280D02*
X446480Y223900D01*
G01X471700Y196700D02*
X445900Y222500D01*
G01X428504Y544723D02*
Y563227D01*
G01Y544723D02*
G03X437953I4724J0D01*
G01Y563227D02*
Y544723D01*
G01X428505Y544724D02*
Y563228D01*
G01Y544724D02*
G03X437954I4725J0D01*
G01Y563228D02*
Y544724D01*
G01X439922Y565196D02*
X437954Y563228D01*
G01X540828Y565196D02*
X439922D01*
G01X547954Y-73346D02*
X622403D01*
G01X547954D02*
Y-7874D01*
G01X540080Y-71378D02*
Y-3937D01*
G01X538111Y-73346D02*
X540080Y-71378D01*
G01X558662Y9505D02*
Y155374D01*
G01X557509Y6721D02*
G03X558662Y9505I-2784J2784D01*
G01X551942Y1153D02*
X557509Y6721D01*
G01X549158Y0D02*
G03X551942Y1153I0J3937D01*
G01X544017Y0D02*
X549158D01*
G01X544017D02*
G03X540080Y-3937I0J-3937D01*
G01X547954Y-7874D02*
X549158D01*
G01Y0D02*
G03X551942Y1153I0J3937D01*
G01X549158Y-7875D02*
G03X557510Y-4415I0J11811D01*
G01X551942Y1153D02*
X557509Y6721D01*
G01X557510Y-4414D02*
X563077Y1154D01*
G01X557509Y6721D02*
G03X558662Y9505I-2784J2784D01*
G01X563077Y1153D02*
G03X566536Y9507I-8352J8351D01*
G01X558662Y9505D02*
Y155374D01*
G01X566536Y9505D02*
Y18655D01*
G01D02*
G03X558662I-3937J-1D01*
G01Y49363D02*
G03X566536I3937J0D01*
G01D02*
Y151437D01*
G01X562599Y159311D02*
X611812D01*
G01X562599D02*
G03X558662Y155374I0J-3937D01*
G01X562599Y159311D02*
G03X558662Y155374I0J-3937D01*
G01X562599Y159311D02*
X611812D01*
G01X566536Y151437D02*
X574076D01*
G01D02*
G03Y159311I0J3937D01*
G01X564353Y249862D02*
G03Y241988I0J-3937D01*
G01X521844D02*
G03Y249862I0J3937D01*
G01X542796Y495787D02*
Y563228D01*
G01Y495787D02*
G03X546733Y491850I3937J0D01*
G01X606244D02*
X546733D01*
G01X606244D02*
X546733D01*
G01X542796Y495787D02*
G03X546733Y491850I3937J0D01*
G01X550670Y499724D02*
Y563622D01*
G01X570124Y491850D02*
G03Y499724I0J3937D01*
G01D02*
X550670D01*
G01Y565196D02*
X622403D01*
G01X542796Y563228D02*
X540828Y565196D01*
G01X550670Y563622D02*
Y565196D01*
G01X622403Y-73346D02*
G03X637403Y-58346I0J15000D01*
G01Y253799D02*
Y-58346D01*
G01X615749Y163248D02*
Y228546D01*
G01X611812Y159311D02*
G03X615749Y163248I0J3937D01*
G01X611812Y159311D02*
G03X615749Y163248I0J3937D01*
G01X611812Y151437D02*
G03X623623Y163248I0J11811D01*
G01X615749D02*
Y228546D01*
G01X623623Y163248D02*
Y228546D01*
G01X604785Y159311D02*
G03Y151437I0J-3937D01*
G01D02*
X611812D01*
G01X615749Y253799D02*
Y482345D01*
G01X611812Y249862D02*
G03X615749Y253799I0J3937D01*
G01X605091Y240835D02*
G03X602307Y241988I-2784J-2784D01*
G01X614596Y231330D02*
X605091Y240835D01*
G01X615749Y228546D02*
G03X614596Y231330I-3937J0D01*
G01X615749Y228546D02*
G03X614596Y231330I-3937J0D01*
G01D02*
X605091Y240835D01*
G01D02*
G03X602307Y241988I-2784J-2784D01*
G01X611812Y249862D02*
G03X615749Y253799I0J3937D01*
G01D02*
Y482345D01*
G01X623623Y253799D02*
Y274659D01*
G01X637403Y253799D02*
Y482345D01*
G01X623623Y228546D02*
Y253799D01*
G01Y274659D02*
G03X615749I-3937J0D01*
G01Y305368D02*
G03X623623I3937J0D01*
G01D02*
Y410289D01*
G01D02*
G03X615749I-3937J0D01*
G01X609028Y490697D02*
G03X606244Y491850I-2784J-2784D01*
G01X614596Y485129D02*
X609028Y490697D01*
G01X615749Y482345D02*
G03X614596Y485129I-3937J0D01*
G01X615749Y482345D02*
G03X614596Y485129I-3937J0D01*
G01X623623Y482345D02*
G03X620164Y490697I-11811J1D01*
G01X614596Y485129D02*
X609028Y490697D01*
G01X620164D02*
X614596Y496265D01*
G01X609028Y490697D02*
G03X606244Y491850I-2784J-2784D01*
G01X614596Y496265D02*
G03X606244Y499724I-8351J-8352D01*
G01D02*
X600833D01*
G01X637403Y482345D02*
Y550196D01*
G01X600833Y499724D02*
G03Y491850I0J-3937D01*
G01X615749Y440998D02*
G03X623623I3937J0D01*
G01D02*
Y482345D01*
G01X637403Y550196D02*
G03X622403Y565196I-15000J0D01*
G54D12*
G01X-15353Y-106096D02*
Y-123596D01*
G01X-20375Y-106096D02*
X-10331D01*
G01X-1565Y-123596D02*
Y-106096D01*
G01Y-114554D02*
X-473Y-113096D01*
X619Y-112221D01*
X2365Y-111930D01*
X3675Y-112221D01*
X5204Y-113388D01*
X5859Y-115138D01*
Y-123596D01*
G01X19647Y-111930D02*
Y-123596D01*
G01Y-107263D02*
X19210Y-106971D01*
Y-106388D01*
X19647Y-106096D01*
X20084Y-106388D01*
Y-106971D01*
X19647Y-107263D01*
G01X33872Y-121555D02*
X34964Y-122721D01*
X36492Y-123596D01*
X37802D01*
X39112Y-123013D01*
X39985Y-122138D01*
X40422Y-120972D01*
X40204Y-119221D01*
X39330Y-118346D01*
X35400Y-116596D01*
X34527Y-114554D01*
X34964Y-113096D01*
X35837Y-112221D01*
X37147Y-111930D01*
X38457Y-112221D01*
X39767Y-113096D01*
G01X69090Y-127971D02*
X70619Y-129138D01*
X72365Y-129429D01*
X73893Y-129138D01*
X75204Y-127680D01*
X76077Y-125638D01*
Y-111930D01*
G01Y-114263D02*
X75204Y-113096D01*
X73893Y-112221D01*
X72365Y-111930D01*
X70619Y-112513D01*
X69527Y-113679D01*
X68653Y-115721D01*
X68217Y-117763D01*
X68435Y-119513D01*
X69309Y-121555D01*
X70619Y-123013D01*
X72365Y-123596D01*
X73675Y-123304D01*
X75204Y-122138D01*
X76077Y-120972D01*
G01X86372Y-115721D02*
X93359D01*
X92704Y-113679D01*
X91612Y-112513D01*
X90084Y-111930D01*
X88555Y-112221D01*
X87245Y-113096D01*
X86372Y-115138D01*
X85935Y-116888D01*
Y-118638D01*
X86372Y-120388D01*
X87464Y-122138D01*
X88774Y-123304D01*
X90302Y-123596D01*
X91830Y-123013D01*
X93359Y-121263D01*
G01X104090Y-123596D02*
Y-111930D01*
G01Y-114263D02*
X105182Y-113096D01*
X106274Y-112221D01*
X107802Y-111930D01*
X108893Y-112221D01*
X110204Y-113096D01*
G01X120717Y-123596D02*
Y-106096D01*
G01Y-114846D02*
X121809Y-113096D01*
X123119Y-112221D01*
X124429Y-111930D01*
X126393Y-112513D01*
X127704Y-113679D01*
X128577Y-115721D01*
Y-118054D01*
X128140Y-120388D01*
X127267Y-122138D01*
X125739Y-123304D01*
X124429Y-123596D01*
X123119Y-123304D01*
X121809Y-122430D01*
X120717Y-120972D01*
G01X138872Y-115721D02*
X145859D01*
X145204Y-113679D01*
X144112Y-112513D01*
X142584Y-111930D01*
X141055Y-112221D01*
X139745Y-113096D01*
X138872Y-115138D01*
X138435Y-116888D01*
Y-118638D01*
X138872Y-120388D01*
X139964Y-122138D01*
X141274Y-123304D01*
X142802Y-123596D01*
X144330Y-123013D01*
X145859Y-121263D01*
G01X156590Y-123596D02*
Y-111930D01*
G01Y-114263D02*
X157682Y-113096D01*
X158774Y-112221D01*
X160302Y-111930D01*
X161393Y-112221D01*
X162704Y-113096D01*
G01X194647Y-111930D02*
Y-123596D01*
G01Y-107263D02*
X194210Y-106971D01*
Y-106388D01*
X194647Y-106096D01*
X195084Y-106388D01*
Y-106971D01*
X194647Y-107263D01*
G01X208872Y-121555D02*
X209964Y-122721D01*
X211492Y-123596D01*
X212802D01*
X214112Y-123013D01*
X214985Y-122138D01*
X215422Y-120972D01*
X215204Y-119221D01*
X214330Y-118346D01*
X210400Y-116596D01*
X209527Y-114554D01*
X209964Y-113096D01*
X210837Y-112221D01*
X212147Y-111930D01*
X213457Y-112221D01*
X214767Y-113096D01*
G01X243653Y-127971D02*
X245182Y-129138D01*
X246492Y-129429D01*
X248239Y-128846D01*
X249549Y-127388D01*
X250204Y-124762D01*
Y-111930D01*
G01Y-107263D02*
X249767Y-106971D01*
Y-106388D01*
X250204Y-106096D01*
X250640Y-106388D01*
Y-106971D01*
X250204Y-107263D01*
G01X260935Y-111930D02*
Y-120096D01*
X261809Y-122138D01*
X263119Y-123304D01*
X264647Y-123596D01*
X266175Y-123304D01*
X267485Y-122138D01*
X268359Y-120096D01*
G01Y-123596D02*
Y-111930D01*
G01X278872Y-121555D02*
X279964Y-122721D01*
X281492Y-123596D01*
X282802D01*
X284112Y-123013D01*
X284985Y-122138D01*
X285422Y-120972D01*
X285204Y-119221D01*
X284330Y-118346D01*
X280400Y-116596D01*
X279527Y-114554D01*
X279964Y-113096D01*
X280837Y-112221D01*
X282147Y-111930D01*
X283457Y-112221D01*
X284767Y-113096D01*
G01X299647Y-106096D02*
Y-123596D01*
G01X296590Y-111930D02*
X302704D01*
G01X333337Y-123596D02*
Y-108721D01*
X333774Y-107263D01*
X334647Y-106388D01*
X335957Y-106096D01*
X337267Y-106679D01*
X337922Y-108138D01*
G01X335302Y-113096D02*
X330935D01*
G01X352147Y-123596D02*
X350837Y-123304D01*
X349527Y-122138D01*
X348653Y-120096D01*
X348217Y-117763D01*
X348653Y-115429D01*
X349527Y-113388D01*
X350837Y-112221D01*
X352147Y-111930D01*
X353457Y-112221D01*
X354767Y-113388D01*
X355640Y-115429D01*
X355859Y-117763D01*
X355640Y-120096D01*
X354767Y-122138D01*
X353457Y-123304D01*
X352147Y-123596D01*
G01X366590D02*
Y-111930D01*
G01Y-114263D02*
X367682Y-113096D01*
X368774Y-112221D01*
X370302Y-111930D01*
X371393Y-112221D01*
X372704Y-113096D01*
G01X400062Y-128846D02*
X401372Y-129429D01*
X403119Y-128846D01*
X404210Y-127680D01*
X405084Y-126221D01*
X406393Y-121555D01*
X409232Y-111930D01*
G01X402245D02*
X406393Y-121555D01*
G01X422147Y-123596D02*
X420837Y-123304D01*
X419527Y-122138D01*
X418653Y-120096D01*
X418217Y-117763D01*
X418653Y-115429D01*
X419527Y-113388D01*
X420837Y-112221D01*
X422147Y-111930D01*
X423457Y-112221D01*
X424767Y-113388D01*
X425640Y-115429D01*
X425859Y-117763D01*
X425640Y-120096D01*
X424767Y-122138D01*
X423457Y-123304D01*
X422147Y-123596D01*
G01X435935Y-111930D02*
Y-120096D01*
X436809Y-122138D01*
X438119Y-123304D01*
X439647Y-123596D01*
X441175Y-123304D01*
X442485Y-122138D01*
X443359Y-120096D01*
G01Y-123596D02*
Y-111930D01*
G01X454090Y-123596D02*
Y-111930D01*
G01Y-114263D02*
X455182Y-113096D01*
X456274Y-112221D01*
X457802Y-111930D01*
X458893Y-112221D01*
X460204Y-113096D01*
G01X489090Y-123596D02*
Y-111930D01*
G01Y-114263D02*
X490182Y-113096D01*
X491274Y-112221D01*
X492802Y-111930D01*
X493893Y-112221D01*
X495204Y-113096D01*
G01X506372Y-115721D02*
X513359D01*
X512704Y-113679D01*
X511612Y-112513D01*
X510084Y-111930D01*
X508555Y-112221D01*
X507245Y-113096D01*
X506372Y-115138D01*
X505935Y-116888D01*
Y-118638D01*
X506372Y-120388D01*
X507464Y-122138D01*
X508774Y-123304D01*
X510302Y-123596D01*
X511830Y-123013D01*
X513359Y-121263D01*
G01X525837Y-123596D02*
Y-108721D01*
X526274Y-107263D01*
X527147Y-106388D01*
X528457Y-106096D01*
X529767Y-106679D01*
X530422Y-108138D01*
G01X527802Y-113096D02*
X523435D01*
G01X541372Y-115721D02*
X548359D01*
X547704Y-113679D01*
X546612Y-112513D01*
X545084Y-111930D01*
X543555Y-112221D01*
X542245Y-113096D01*
X541372Y-115138D01*
X540935Y-116888D01*
Y-118638D01*
X541372Y-120388D01*
X542464Y-122138D01*
X543774Y-123304D01*
X545302Y-123596D01*
X546830Y-123013D01*
X548359Y-121263D01*
G01X559090Y-123596D02*
Y-111930D01*
G01Y-114263D02*
X560182Y-113096D01*
X561274Y-112221D01*
X562802Y-111930D01*
X563893Y-112221D01*
X565204Y-113096D01*
G01X576372Y-115721D02*
X583359D01*
X582704Y-113679D01*
X581612Y-112513D01*
X580084Y-111930D01*
X578555Y-112221D01*
X577245Y-113096D01*
X576372Y-115138D01*
X575935Y-116888D01*
Y-118638D01*
X576372Y-120388D01*
X577464Y-122138D01*
X578774Y-123304D01*
X580302Y-123596D01*
X581830Y-123013D01*
X583359Y-121263D01*
G01X593435Y-123596D02*
Y-111930D01*
G01Y-114846D02*
X594309Y-113388D01*
X595619Y-112221D01*
X597365Y-111930D01*
X598893Y-112221D01*
X600204Y-113388D01*
X600859Y-115429D01*
Y-123596D01*
G01X618140Y-113388D02*
X616612Y-112221D01*
X615302Y-111930D01*
X613555Y-112513D01*
X612245Y-113679D01*
X611372Y-115721D01*
X611153Y-117763D01*
X611372Y-119805D01*
X612245Y-121555D01*
X613555Y-123013D01*
X615302Y-123596D01*
X616830Y-123013D01*
X618140Y-121846D01*
G01X628872Y-115721D02*
X635859D01*
X635204Y-113679D01*
X634112Y-112513D01*
X632584Y-111930D01*
X631055Y-112221D01*
X629745Y-113096D01*
X628872Y-115138D01*
X628435Y-116888D01*
Y-118638D01*
X628872Y-120388D01*
X629964Y-122138D01*
X631274Y-123304D01*
X632802Y-123596D01*
X634330Y-123013D01*
X635859Y-121263D01*
G01X667147Y-106096D02*
Y-123596D01*
G01X664090Y-111930D02*
X670204D01*
G01X684647Y-123596D02*
X683337Y-123304D01*
X682027Y-122138D01*
X681153Y-120096D01*
X680717Y-117763D01*
X681153Y-115429D01*
X682027Y-113388D01*
X683337Y-112221D01*
X684647Y-111930D01*
X685957Y-112221D01*
X687267Y-113388D01*
X688140Y-115429D01*
X688359Y-117763D01*
X688140Y-120096D01*
X687267Y-122138D01*
X685957Y-123304D01*
X684647Y-123596D01*
G01X718337D02*
Y-108721D01*
X718774Y-107263D01*
X719647Y-106388D01*
X720957Y-106096D01*
X722267Y-106679D01*
X722922Y-108138D01*
G01X720302Y-113096D02*
X715935D01*
G01X737147Y-111930D02*
Y-123596D01*
G01Y-107263D02*
X736710Y-106971D01*
Y-106388D01*
X737147Y-106096D01*
X737584Y-106388D01*
Y-106971D01*
X737147Y-107263D01*
G01X750935Y-123596D02*
Y-111930D01*
G01Y-114846D02*
X751809Y-113388D01*
X753119Y-112221D01*
X754865Y-111930D01*
X756393Y-112221D01*
X757704Y-113388D01*
X758359Y-115429D01*
Y-123596D01*
G01X776077Y-106096D02*
Y-123596D01*
G01Y-120972D02*
X775204Y-122430D01*
X773893Y-123304D01*
X772365Y-123596D01*
X770619Y-123013D01*
X769309Y-121555D01*
X768435Y-119805D01*
X768217Y-117763D01*
X768435Y-115721D01*
X769309Y-113971D01*
X770619Y-112513D01*
X772365Y-111930D01*
X773893Y-112221D01*
X774985Y-112805D01*
X776077Y-113971D01*
G01X807147Y-106096D02*
Y-123596D01*
G01X804090Y-111930D02*
X810204D01*
G01X820935Y-123596D02*
Y-106096D01*
G01Y-114554D02*
X822027Y-113096D01*
X823119Y-112221D01*
X824865Y-111930D01*
X826175Y-112221D01*
X827704Y-113388D01*
X828359Y-115138D01*
Y-123596D01*
G01X838872Y-115721D02*
X845859D01*
X845204Y-113679D01*
X844112Y-112513D01*
X842584Y-111930D01*
X841055Y-112221D01*
X839745Y-113096D01*
X838872Y-115138D01*
X838435Y-116888D01*
Y-118638D01*
X838872Y-120388D01*
X839964Y-122138D01*
X841274Y-123304D01*
X842802Y-123596D01*
X844330Y-123013D01*
X845859Y-121263D01*
G01X872344Y-123596D02*
Y-106096D01*
X876710D01*
X878457Y-106971D01*
X879767Y-108138D01*
X880859Y-109887D01*
X881732Y-111930D01*
X881950Y-114846D01*
X881732Y-117763D01*
X880859Y-119805D01*
X879767Y-121555D01*
X878457Y-122721D01*
X876710Y-123596D01*
X872344D01*
G01X890280D02*
Y-106096D01*
X895520D01*
X897267Y-106971D01*
X898577Y-109013D01*
X899014Y-111346D01*
X898577Y-113679D01*
X897485Y-115429D01*
X895520Y-116305D01*
X890280D01*
G01X929647Y-111930D02*
Y-123596D01*
G01Y-107263D02*
X929210Y-106971D01*
Y-106388D01*
X929647Y-106096D01*
X930084Y-106388D01*
Y-106971D01*
X929647Y-107263D01*
G01X940597Y-123596D02*
Y-111930D01*
G01Y-115138D02*
X941252Y-113679D01*
X942344Y-112513D01*
X943872Y-111930D01*
X945400Y-112513D01*
X946492Y-113679D01*
X947147Y-115138D01*
Y-123596D01*
G01Y-115138D02*
X947802Y-113679D01*
X948893Y-112513D01*
X950422Y-111930D01*
X951950Y-112513D01*
X953042Y-113679D01*
X953697Y-115429D01*
Y-123596D01*
G01X960717Y-129429D02*
Y-111930D01*
G01Y-114554D02*
X961809Y-113096D01*
X962900Y-112221D01*
X964647Y-111930D01*
X966175Y-112221D01*
X967704Y-113679D01*
X968359Y-115721D01*
X968577Y-117763D01*
X968359Y-119805D01*
X967704Y-121846D01*
X966393Y-123013D01*
X964647Y-123596D01*
X963119Y-123304D01*
X961590Y-122430D01*
X960717Y-121263D01*
G01X978872Y-115721D02*
X985859D01*
X985204Y-113679D01*
X984112Y-112513D01*
X982584Y-111930D01*
X981055Y-112221D01*
X979745Y-113096D01*
X978872Y-115138D01*
X978435Y-116888D01*
Y-118638D01*
X978872Y-120388D01*
X979964Y-122138D01*
X981274Y-123304D01*
X982802Y-123596D01*
X984330Y-123013D01*
X985859Y-121263D01*
G01X1003577Y-106096D02*
Y-123596D01*
G01Y-120972D02*
X1002704Y-122430D01*
X1001393Y-123304D01*
X999865Y-123596D01*
X998119Y-123013D01*
X996809Y-121555D01*
X995935Y-119805D01*
X995717Y-117763D01*
X995935Y-115721D01*
X996809Y-113971D01*
X998119Y-112513D01*
X999865Y-111930D01*
X1001393Y-112221D01*
X1002485Y-112805D01*
X1003577Y-113971D01*
G01X1021077Y-123596D02*
Y-111930D01*
G01Y-113971D02*
X1020204Y-112805D01*
X1018893Y-112221D01*
X1017365Y-111930D01*
X1015837Y-112513D01*
X1014527Y-113679D01*
X1013653Y-115429D01*
X1013217Y-117763D01*
X1013653Y-120096D01*
X1014527Y-121846D01*
X1015837Y-123013D01*
X1017365Y-123596D01*
X1018893Y-123304D01*
X1020204Y-122430D01*
X1021077Y-121263D01*
G01X1030935Y-123596D02*
Y-111930D01*
G01Y-114846D02*
X1031809Y-113388D01*
X1033119Y-112221D01*
X1034865Y-111930D01*
X1036393Y-112221D01*
X1037704Y-113388D01*
X1038359Y-115429D01*
Y-123596D01*
G01X1055640Y-113388D02*
X1054112Y-112221D01*
X1052802Y-111930D01*
X1051055Y-112513D01*
X1049745Y-113679D01*
X1048872Y-115721D01*
X1048653Y-117763D01*
X1048872Y-119805D01*
X1049745Y-121555D01*
X1051055Y-123013D01*
X1052802Y-123596D01*
X1054330Y-123013D01*
X1055640Y-121846D01*
G01X1066372Y-115721D02*
X1073359D01*
X1072704Y-113679D01*
X1071612Y-112513D01*
X1070084Y-111930D01*
X1068555Y-112221D01*
X1067245Y-113096D01*
X1066372Y-115138D01*
X1065935Y-116888D01*
Y-118638D01*
X1066372Y-120388D01*
X1067464Y-122138D01*
X1068774Y-123304D01*
X1070302Y-123596D01*
X1071830Y-123013D01*
X1073359Y-121263D01*
G01X1104647Y-106096D02*
Y-123596D01*
G01X1101590Y-111930D02*
X1107704D01*
G01X1119090Y-123596D02*
Y-111930D01*
G01Y-114263D02*
X1120182Y-113096D01*
X1121274Y-112221D01*
X1122802Y-111930D01*
X1123893Y-112221D01*
X1125204Y-113096D01*
G01X1143577Y-123596D02*
Y-111930D01*
G01Y-113971D02*
X1142704Y-112805D01*
X1141393Y-112221D01*
X1139865Y-111930D01*
X1138337Y-112513D01*
X1137027Y-113679D01*
X1136153Y-115429D01*
X1135717Y-117763D01*
X1136153Y-120096D01*
X1137027Y-121846D01*
X1138337Y-123013D01*
X1139865Y-123596D01*
X1141393Y-123304D01*
X1142704Y-122430D01*
X1143577Y-121263D01*
G01X1160640Y-113388D02*
X1159112Y-112221D01*
X1157802Y-111930D01*
X1156055Y-112513D01*
X1154745Y-113679D01*
X1153872Y-115721D01*
X1153653Y-117763D01*
X1153872Y-119805D01*
X1154745Y-121555D01*
X1156055Y-123013D01*
X1157802Y-123596D01*
X1159330Y-123013D01*
X1160640Y-121846D01*
G01X1171372Y-115721D02*
X1178359D01*
X1177704Y-113679D01*
X1176612Y-112513D01*
X1175084Y-111930D01*
X1173555Y-112221D01*
X1172245Y-113096D01*
X1171372Y-115138D01*
X1170935Y-116888D01*
Y-118638D01*
X1171372Y-120388D01*
X1172464Y-122138D01*
X1173774Y-123304D01*
X1175302Y-123596D01*
X1176830Y-123013D01*
X1178359Y-121263D01*
G01X1188872Y-121555D02*
X1189964Y-122721D01*
X1191492Y-123596D01*
X1192802D01*
X1194112Y-123013D01*
X1194985Y-122138D01*
X1195422Y-120972D01*
X1195204Y-119221D01*
X1194330Y-118346D01*
X1190400Y-116596D01*
X1189527Y-114554D01*
X1189964Y-113096D01*
X1190837Y-112221D01*
X1192147Y-111930D01*
X1193457Y-112221D01*
X1194767Y-113096D01*
G01X1227147Y-111930D02*
Y-123596D01*
G01Y-107263D02*
X1226710Y-106971D01*
Y-106388D01*
X1227147Y-106096D01*
X1227584Y-106388D01*
Y-106971D01*
X1227147Y-107263D01*
G01X1240935Y-123596D02*
Y-111930D01*
G01Y-114846D02*
X1241809Y-113388D01*
X1243119Y-112221D01*
X1244865Y-111930D01*
X1246393Y-112221D01*
X1247704Y-113388D01*
X1248359Y-115429D01*
Y-123596D01*
G01X1279647D02*
Y-106096D01*
G01X1301077Y-123596D02*
Y-111930D01*
G01Y-113971D02*
X1300204Y-112805D01*
X1298893Y-112221D01*
X1297365Y-111930D01*
X1295837Y-112513D01*
X1294527Y-113679D01*
X1293653Y-115429D01*
X1293217Y-117763D01*
X1293653Y-120096D01*
X1294527Y-121846D01*
X1295837Y-123013D01*
X1297365Y-123596D01*
X1298893Y-123304D01*
X1300204Y-122430D01*
X1301077Y-121263D01*
G01X1310062Y-128846D02*
X1311372Y-129429D01*
X1313119Y-128846D01*
X1314210Y-127680D01*
X1315084Y-126221D01*
X1316393Y-121555D01*
X1319232Y-111930D01*
G01X1312245D02*
X1316393Y-121555D01*
G01X1328872Y-115721D02*
X1335859D01*
X1335204Y-113679D01*
X1334112Y-112513D01*
X1332584Y-111930D01*
X1331055Y-112221D01*
X1329745Y-113096D01*
X1328872Y-115138D01*
X1328435Y-116888D01*
Y-118638D01*
X1328872Y-120388D01*
X1329964Y-122138D01*
X1331274Y-123304D01*
X1332802Y-123596D01*
X1334330Y-123013D01*
X1335859Y-121263D01*
G01X1346590Y-123596D02*
Y-111930D01*
G01Y-114263D02*
X1347682Y-113096D01*
X1348774Y-112221D01*
X1350302Y-111930D01*
X1351393Y-112221D01*
X1352704Y-113096D01*
G01X1380280Y-106096D02*
Y-123596D01*
X1389014D01*
G01X1404767D02*
Y-106096D01*
X1396688Y-118638D01*
X1407606D01*
G01X1419647Y-124179D02*
X1419210Y-123888D01*
Y-123304D01*
X1419647Y-123013D01*
X1420084Y-123304D01*
Y-123888D01*
X1419647Y-124179D01*
G01X735350Y470663D02*
X744956Y483496D01*
G01X740153Y485829D02*
Y468329D01*
G01X744956Y470663D02*
X735350Y483496D01*
G01X733603Y477079D02*
X746703D01*
G01X757653Y471246D02*
X759181Y471538D01*
X760928Y472412D01*
X762020Y473870D01*
X762456Y475913D01*
X762020Y477954D01*
X760710Y479704D01*
X758745Y480579D01*
X756561D01*
X755251Y481163D01*
X754159Y482621D01*
X753723Y484662D01*
X754378Y486704D01*
X755906Y488163D01*
X757653Y488746D01*
X759399Y488163D01*
X760928Y486704D01*
X761583Y484662D01*
X761146Y482621D01*
X760055Y481163D01*
X758745Y480579D01*
X756561D01*
X754596Y479704D01*
X753286Y477954D01*
X752850Y475913D01*
X753286Y473870D01*
X754378Y472412D01*
X756125Y471538D01*
X757653Y471246D01*
G01X770350Y473870D02*
X771659Y472412D01*
X773188Y471538D01*
X775153Y471246D01*
X777118Y471829D01*
X778646Y472996D01*
X779738Y475037D01*
X779956Y477371D01*
X779520Y479704D01*
X778428Y481163D01*
X776899Y482329D01*
X775371Y482621D01*
X773843Y482329D01*
X771878Y481163D01*
X772533Y488746D01*
X778428D01*
G01X792653Y470663D02*
X792216Y470954D01*
Y471538D01*
X792653Y471829D01*
X793090Y471538D01*
Y470954D01*
X792653Y470663D01*
G01X810153Y488746D02*
X808406Y488163D01*
X807096Y486704D01*
X806223Y484955D01*
X805568Y482621D01*
X805350Y479996D01*
X805568Y477371D01*
X806223Y475037D01*
X807096Y473287D01*
X808406Y471829D01*
X810153Y471246D01*
X811899Y471829D01*
X813210Y473287D01*
X814083Y475037D01*
X814738Y477371D01*
X814956Y479996D01*
X814738Y482621D01*
X814083Y484955D01*
X813210Y486704D01*
X811899Y488163D01*
X810153Y488746D01*
G01X745191Y438637D02*
X746720Y437179D01*
X748466Y436596D01*
X750213Y437179D01*
X751741Y438929D01*
X752833Y441554D01*
X753270Y444179D01*
Y447387D01*
X752833Y450012D01*
X751741Y452346D01*
X750431Y453513D01*
X748903Y454096D01*
X747156Y453513D01*
X745846Y452346D01*
X744973Y450596D01*
X744536Y448262D01*
X744973Y446221D01*
X746065Y444179D01*
X747375Y443012D01*
X748903Y442721D01*
X750649Y443304D01*
X751960Y444763D01*
X753270Y447387D01*
G01X766403Y454096D02*
X764656Y453513D01*
X763346Y452054D01*
X762473Y450305D01*
X761818Y447971D01*
X761600Y445346D01*
X761818Y442721D01*
X762473Y440387D01*
X763346Y438637D01*
X764656Y437179D01*
X766403Y436596D01*
X768149Y437179D01*
X769460Y438637D01*
X770333Y440387D01*
X770988Y442721D01*
X771206Y445346D01*
X770988Y447971D01*
X770333Y450305D01*
X769460Y452054D01*
X768149Y453513D01*
X766403Y454096D01*
G01X783903Y436013D02*
X783466Y436304D01*
Y436888D01*
X783903Y437179D01*
X784340Y436888D01*
Y436304D01*
X783903Y436013D01*
G01X801403Y454096D02*
X799656Y453513D01*
X798346Y452054D01*
X797473Y450305D01*
X796818Y447971D01*
X796600Y445346D01*
X796818Y442721D01*
X797473Y440387D01*
X798346Y438637D01*
X799656Y437179D01*
X801403Y436596D01*
X803149Y437179D01*
X804460Y438637D01*
X805333Y440387D01*
X805988Y442721D01*
X806206Y445346D01*
X805988Y447971D01*
X805333Y450305D01*
X804460Y452054D01*
X803149Y453513D01*
X801403Y454096D01*
G01X689400Y540546D02*
Y558046D01*
X693766D01*
X695513Y557171D01*
X696823Y556004D01*
X697915Y554255D01*
X698788Y552212D01*
X699006Y549296D01*
X698788Y546379D01*
X697915Y544337D01*
X696823Y542587D01*
X695513Y541421D01*
X693766Y540546D01*
X689400D01*
G01X707336D02*
Y558046D01*
X712576D01*
X714323Y557171D01*
X715633Y555129D01*
X716070Y552796D01*
X715633Y550463D01*
X714541Y548713D01*
X712576Y547837D01*
X707336D01*
G01X744083Y558046D02*
X749323D01*
G01X746703D02*
Y540546D01*
G01X744083D02*
X749323D01*
G01X758526D02*
Y558046D01*
X764203Y543463D01*
X769880Y558046D01*
Y540546D01*
G01X777336D02*
Y558046D01*
X782576D01*
X784323Y557171D01*
X785633Y555129D01*
X786070Y552796D01*
X785633Y550463D01*
X784541Y548713D01*
X782576Y547837D01*
X777336D01*
G01X803570Y540546D02*
X794836D01*
Y558046D01*
X803570D01*
G01X800076Y549588D02*
X794836D01*
G01X811900Y540546D02*
Y558046D01*
X816266D01*
X818013Y557171D01*
X819323Y556004D01*
X820415Y554255D01*
X821288Y552212D01*
X821506Y549296D01*
X821288Y546379D01*
X820415Y544337D01*
X819323Y542587D01*
X818013Y541421D01*
X816266Y540546D01*
X811900D01*
G01X828744D02*
X834203Y558046D01*
X839662Y540546D01*
G01X837696Y546671D02*
X830709D01*
G01X846681Y540546D02*
Y558046D01*
X856725Y540546D01*
Y558046D01*
G01X874006Y556587D02*
X872696Y557463D01*
X871168Y558046D01*
X869421D01*
X867456Y557171D01*
X865928Y555713D01*
X864836Y553962D01*
X863963Y551046D01*
X863744Y548421D01*
X864181Y545796D01*
X864836Y544046D01*
X866146Y542296D01*
X867675Y541129D01*
X869203Y540546D01*
X870731D01*
X872260Y541129D01*
X873570Y542004D01*
X874662Y543170D01*
G01X891070Y540546D02*
X882336D01*
Y558046D01*
X891070D01*
G01X887576Y549588D02*
X882336D01*
G01X921703Y558046D02*
Y540546D01*
G01X916681Y558046D02*
X926725D01*
G01X933744Y540546D02*
X939203Y558046D01*
X944662Y540546D01*
G01X942696Y546671D02*
X935709D01*
G01X958449Y549879D02*
X959323Y550754D01*
X959978Y552212D01*
X960415Y554255D01*
X959978Y556004D01*
X959105Y557171D01*
X957576Y558046D01*
X951681D01*
Y540546D01*
X958886D01*
X960415Y541712D01*
X961288Y543463D01*
X961725Y545504D01*
X961288Y547546D01*
X959978Y549296D01*
X958449Y549879D01*
X951681D01*
G01X969836Y558046D02*
Y540546D01*
X978570D01*
G01X996070D02*
X987336D01*
Y558046D01*
X996070D01*
G01X992576Y549588D02*
X987336D01*
G01X1009203Y539963D02*
X1008766Y540254D01*
Y540838D01*
X1009203Y541129D01*
X1009640Y540838D01*
Y540254D01*
X1009203Y539963D01*
G01Y547837D02*
X1008766Y548129D01*
Y548713D01*
X1009203Y549004D01*
X1009640Y548713D01*
Y548129D01*
X1009203Y547837D01*
G01X1039836Y558046D02*
Y540546D01*
X1048570D01*
G01X1064323D02*
Y558046D01*
X1056244Y545504D01*
X1067162D01*
G01X711283Y523396D02*
X716523D01*
G01X713903D02*
Y505896D01*
G01X711283D02*
X716523D01*
G01X725726D02*
Y523396D01*
X731403Y508813D01*
X737080Y523396D01*
Y505896D01*
G01X744536D02*
Y523396D01*
X749776D01*
X751523Y522521D01*
X752833Y520479D01*
X753270Y518146D01*
X752833Y515813D01*
X751741Y514063D01*
X749776Y513187D01*
X744536D01*
G01X765311Y500063D02*
X763128Y502979D01*
X762036Y505896D01*
Y517562D01*
X763128Y520479D01*
X765311Y523396D01*
G01X783903Y505896D02*
X782156Y506188D01*
X780628Y507354D01*
X779318Y509104D01*
X778444Y511146D01*
X778008Y513479D01*
Y515813D01*
X778444Y518146D01*
X779318Y520188D01*
X780628Y521937D01*
X782156Y523104D01*
X783903Y523396D01*
X785649Y523104D01*
X787178Y521937D01*
X788488Y520188D01*
X789362Y518146D01*
X789798Y515813D01*
Y513479D01*
X789362Y511146D01*
X788488Y509104D01*
X787178Y507354D01*
X785649Y506188D01*
X783903Y505896D01*
G01X797691D02*
Y523396D01*
G01Y514938D02*
X798783Y516396D01*
X799875Y517271D01*
X801621Y517562D01*
X802931Y517271D01*
X804460Y516104D01*
X805115Y514354D01*
Y505896D01*
G01X812353D02*
Y517562D01*
G01Y514354D02*
X813008Y515813D01*
X814100Y516979D01*
X815628Y517562D01*
X817156Y516979D01*
X818248Y515813D01*
X818903Y514354D01*
Y505896D01*
G01Y514354D02*
X819558Y515813D01*
X820649Y516979D01*
X822178Y517562D01*
X823706Y516979D01*
X824798Y515813D01*
X825453Y514063D01*
Y505896D01*
G01X837495Y500063D02*
X839678Y502979D01*
X840770Y505896D01*
Y517562D01*
X839678Y520479D01*
X837495Y523396D01*
G01X891103D02*
X894159Y505896D01*
X897653Y523396D01*
X901146Y505896D01*
X904203Y523396D01*
G01X912533D02*
X917773D01*
G01X915153D02*
Y505896D01*
G01X912533D02*
X917773D01*
G01X927850D02*
Y523396D01*
X932216D01*
X933963Y522521D01*
X935273Y521354D01*
X936365Y519605D01*
X937238Y517562D01*
X937456Y514646D01*
X937238Y511729D01*
X936365Y509687D01*
X935273Y507937D01*
X933963Y506771D01*
X932216Y505896D01*
X927850D01*
G01X950153Y523396D02*
Y505896D01*
G01X945131Y523396D02*
X955175D01*
G01X963068Y505896D02*
Y523396D01*
G01X972238D02*
Y505896D01*
G01Y514646D02*
X963068D01*
G01X984061Y500063D02*
X981878Y502979D01*
X980786Y505896D01*
Y517562D01*
X981878Y520479D01*
X984061Y523396D01*
G01X996103Y505896D02*
Y517562D01*
G01Y514354D02*
X996758Y515813D01*
X997850Y516979D01*
X999378Y517562D01*
X1000906Y516979D01*
X1001998Y515813D01*
X1002653Y514354D01*
Y505896D01*
G01Y514354D02*
X1003308Y515813D01*
X1004399Y516979D01*
X1005928Y517562D01*
X1007456Y516979D01*
X1008548Y515813D01*
X1009203Y514063D01*
Y505896D01*
G01X1020153Y517562D02*
Y505896D01*
G01Y522229D02*
X1019716Y522521D01*
Y523104D01*
X1020153Y523396D01*
X1020590Y523104D01*
Y522521D01*
X1020153Y522229D01*
G01X1037653Y505896D02*
Y523396D01*
G01X1051878Y507937D02*
X1052970Y506771D01*
X1054498Y505896D01*
X1055808D01*
X1057118Y506479D01*
X1057991Y507354D01*
X1058428Y508520D01*
X1058210Y510271D01*
X1057336Y511146D01*
X1053406Y512896D01*
X1052533Y514938D01*
X1052970Y516396D01*
X1053843Y517271D01*
X1055153Y517562D01*
X1056463Y517271D01*
X1057773Y516396D01*
G01X1073745Y500063D02*
X1075928Y502979D01*
X1077020Y505896D01*
Y517562D01*
X1075928Y520479D01*
X1073745Y523396D01*
G01X927850Y473870D02*
X929159Y472412D01*
X930688Y471538D01*
X932653Y471246D01*
X934618Y471829D01*
X936146Y472996D01*
X937238Y475037D01*
X937456Y477371D01*
X937020Y479704D01*
X935928Y481163D01*
X934399Y482329D01*
X932871Y482621D01*
X931343Y482329D01*
X929378Y481163D01*
X930033Y488746D01*
X935928D01*
G01X950153Y470663D02*
X949716Y470954D01*
Y471538D01*
X950153Y471829D01*
X950590Y471538D01*
Y470954D01*
X950153Y470663D01*
G01X967653Y488746D02*
X965906Y488163D01*
X964596Y486704D01*
X963723Y484955D01*
X963068Y482621D01*
X962850Y479996D01*
X963068Y477371D01*
X963723Y475037D01*
X964596Y473287D01*
X965906Y471829D01*
X967653Y471246D01*
X969399Y471829D01*
X970710Y473287D01*
X971583Y475037D01*
X972238Y477371D01*
X972456Y479996D01*
X972238Y482621D01*
X971583Y484955D01*
X970710Y486704D01*
X969399Y488163D01*
X967653Y488746D01*
G01X981223Y470663D02*
X989083Y488746D01*
G01X998505Y478537D02*
X1000033Y480579D01*
X1001343Y481746D01*
X1003090Y482329D01*
X1004618Y481746D01*
X1005710Y480579D01*
X1006583Y478829D01*
X1006801Y476788D01*
X1006583Y475037D01*
X1005710Y473287D01*
X1004399Y471829D01*
X1002871Y471246D01*
X1001125Y471829D01*
X999596Y473579D01*
X998723Y476204D01*
X998505Y479121D01*
X998941Y482912D01*
X999596Y484955D01*
X1000688Y486996D01*
X1002216Y488454D01*
X1003745Y488746D01*
X1005273Y488163D01*
X1006365Y486704D01*
G01X1020153Y470663D02*
X1019716Y470954D01*
Y471538D01*
X1020153Y471829D01*
X1020590Y471538D01*
Y470954D01*
X1020153Y470663D01*
G01X1032850Y473870D02*
X1034159Y472412D01*
X1035688Y471538D01*
X1037653Y471246D01*
X1039618Y471829D01*
X1041146Y472996D01*
X1042238Y475037D01*
X1042456Y477371D01*
X1042020Y479704D01*
X1040928Y481163D01*
X1039399Y482329D01*
X1037871Y482621D01*
X1036343Y482329D01*
X1034378Y481163D01*
X1035033Y488746D01*
X1040928D01*
G01X927850Y439220D02*
X929159Y437762D01*
X930688Y436888D01*
X932653Y436596D01*
X934618Y437179D01*
X936146Y438346D01*
X937238Y440387D01*
X937456Y442721D01*
X937020Y445054D01*
X935928Y446513D01*
X934399Y447679D01*
X932871Y447971D01*
X931343Y447679D01*
X929378Y446513D01*
X930033Y454096D01*
X935928D01*
G01X950153Y436013D02*
X949716Y436304D01*
Y436888D01*
X950153Y437179D01*
X950590Y436888D01*
Y436304D01*
X950153Y436013D01*
G01X967653Y454096D02*
X965906Y453513D01*
X964596Y452054D01*
X963723Y450305D01*
X963068Y447971D01*
X962850Y445346D01*
X963068Y442721D01*
X963723Y440387D01*
X964596Y438637D01*
X965906Y437179D01*
X967653Y436596D01*
X969399Y437179D01*
X970710Y438637D01*
X971583Y440387D01*
X972238Y442721D01*
X972456Y445346D01*
X972238Y447971D01*
X971583Y450305D01*
X970710Y452054D01*
X969399Y453513D01*
X967653Y454096D01*
G01X981223Y436013D02*
X989083Y454096D01*
G01X998941Y438637D02*
X1000470Y437179D01*
X1002216Y436596D01*
X1003963Y437179D01*
X1005491Y438929D01*
X1006583Y441554D01*
X1007020Y444179D01*
Y447387D01*
X1006583Y450012D01*
X1005491Y452346D01*
X1004181Y453513D01*
X1002653Y454096D01*
X1000906Y453513D01*
X999596Y452346D01*
X998723Y450596D01*
X998286Y448262D01*
X998723Y446221D01*
X999815Y444179D01*
X1001125Y443012D01*
X1002653Y442721D01*
X1004399Y443304D01*
X1005710Y444763D01*
X1007020Y447387D01*
G01X1020153Y436013D02*
X1019716Y436304D01*
Y436888D01*
X1020153Y437179D01*
X1020590Y436888D01*
Y436304D01*
X1020153Y436013D01*
G01X1037653Y454096D02*
X1035906Y453513D01*
X1034596Y452054D01*
X1033723Y450305D01*
X1033068Y447971D01*
X1032850Y445346D01*
X1033068Y442721D01*
X1033723Y440387D01*
X1034596Y438637D01*
X1035906Y437179D01*
X1037653Y436596D01*
X1039399Y437179D01*
X1040710Y438637D01*
X1041583Y440387D01*
X1042238Y442721D01*
X1042456Y445346D01*
X1042238Y447971D01*
X1041583Y450305D01*
X1040710Y452054D01*
X1039399Y453513D01*
X1037653Y454096D01*
G01X1146600Y471246D02*
Y488746D01*
X1150966D01*
X1152713Y487871D01*
X1154023Y486704D01*
X1155115Y484955D01*
X1155988Y482912D01*
X1156206Y479996D01*
X1155988Y477079D01*
X1155115Y475037D01*
X1154023Y473287D01*
X1152713Y472121D01*
X1150966Y471246D01*
X1146600D01*
G01X1164536D02*
Y488746D01*
X1169776D01*
X1171523Y487871D01*
X1172833Y485829D01*
X1173270Y483496D01*
X1172833Y481163D01*
X1171741Y479413D01*
X1169776Y478537D01*
X1164536D01*
G01X1146600Y436596D02*
Y454096D01*
X1150966D01*
X1152713Y453221D01*
X1154023Y452054D01*
X1155115Y450305D01*
X1155988Y448262D01*
X1156206Y445346D01*
X1155988Y442429D01*
X1155115Y440387D01*
X1154023Y438637D01*
X1152713Y437471D01*
X1150966Y436596D01*
X1146600D01*
G01X1164536D02*
Y454096D01*
X1169776D01*
X1171523Y453221D01*
X1172833Y451179D01*
X1173270Y448846D01*
X1172833Y446513D01*
X1171741Y444763D01*
X1169776Y443887D01*
X1164536D01*
G01X1133903Y523396D02*
Y505896D01*
G01X1128881Y523396D02*
X1138925D01*
G01X1151403Y505896D02*
Y513771D01*
X1147036Y523396D01*
G01X1155770D02*
X1151403Y513771D01*
G01X1164536Y505896D02*
Y523396D01*
X1169776D01*
X1171523Y522521D01*
X1172833Y520479D01*
X1173270Y518146D01*
X1172833Y515813D01*
X1171741Y514063D01*
X1169776Y513187D01*
X1164536D01*
G01X1190770Y505896D02*
X1182036D01*
Y523396D01*
X1190770D01*
G01X1187276Y514938D02*
X1182036D01*
G01X1339203Y482912D02*
Y471246D01*
G01Y487579D02*
X1338766Y487871D01*
Y488454D01*
X1339203Y488746D01*
X1339640Y488454D01*
Y487871D01*
X1339203Y487579D01*
G01X1353428Y473287D02*
X1354520Y472121D01*
X1356048Y471246D01*
X1357358D01*
X1358668Y471829D01*
X1359541Y472704D01*
X1359978Y473870D01*
X1359760Y475621D01*
X1358886Y476496D01*
X1354956Y478246D01*
X1354083Y480288D01*
X1354520Y481746D01*
X1355393Y482621D01*
X1356703Y482912D01*
X1358013Y482621D01*
X1359323Y481746D01*
G01X1386681Y471246D02*
Y488746D01*
X1396725Y471246D01*
Y488746D01*
G01X1409203Y471246D02*
X1407456Y471538D01*
X1405928Y472704D01*
X1404618Y474454D01*
X1403744Y476496D01*
X1403308Y478829D01*
Y481163D01*
X1403744Y483496D01*
X1404618Y485538D01*
X1405928Y487287D01*
X1407456Y488454D01*
X1409203Y488746D01*
X1410949Y488454D01*
X1412478Y487287D01*
X1413788Y485538D01*
X1414662Y483496D01*
X1415098Y481163D01*
Y478829D01*
X1414662Y476496D01*
X1413788Y474454D01*
X1412478Y472704D01*
X1410949Y471538D01*
X1409203Y471246D01*
G01X1426703Y488746D02*
Y471246D01*
G01X1421681Y488746D02*
X1431725D01*
G01X1457991Y482912D02*
Y474746D01*
X1458865Y472704D01*
X1460175Y471538D01*
X1461703Y471246D01*
X1463231Y471538D01*
X1464541Y472704D01*
X1465415Y474746D01*
G01Y471246D02*
Y482912D01*
G01X1475928Y473287D02*
X1477020Y472121D01*
X1478548Y471246D01*
X1479858D01*
X1481168Y471829D01*
X1482041Y472704D01*
X1482478Y473870D01*
X1482260Y475621D01*
X1481386Y476496D01*
X1477456Y478246D01*
X1476583Y480288D01*
X1477020Y481746D01*
X1477893Y482621D01*
X1479203Y482912D01*
X1480513Y482621D01*
X1481823Y481746D01*
G01X1493428Y479121D02*
X1500415D01*
X1499760Y481163D01*
X1498668Y482329D01*
X1497140Y482912D01*
X1495611Y482621D01*
X1494301Y481746D01*
X1493428Y479704D01*
X1492991Y477954D01*
Y476204D01*
X1493428Y474454D01*
X1494520Y472704D01*
X1495830Y471538D01*
X1497358Y471246D01*
X1498886Y471829D01*
X1500415Y473579D01*
G01X1518133Y488746D02*
Y471246D01*
G01Y473870D02*
X1517260Y472412D01*
X1515949Y471538D01*
X1514421Y471246D01*
X1512675Y471829D01*
X1511365Y473287D01*
X1510491Y475037D01*
X1510273Y477079D01*
X1510491Y479121D01*
X1511365Y480871D01*
X1512675Y482329D01*
X1514421Y482912D01*
X1515949Y482621D01*
X1517041Y482037D01*
X1518133Y480871D01*
G01X1264400Y505313D02*
X1274006Y518146D01*
G01X1269203Y520479D02*
Y502979D01*
G01X1274006Y505313D02*
X1264400Y518146D01*
G01X1262653Y511729D02*
X1275753D01*
G01X1301365D02*
X1307041D01*
G01X1334400Y505896D02*
Y523396D01*
X1338766D01*
X1340513Y522521D01*
X1341823Y521354D01*
X1342915Y519605D01*
X1343788Y517562D01*
X1344006Y514646D01*
X1343788Y511729D01*
X1342915Y509687D01*
X1341823Y507937D01*
X1340513Y506771D01*
X1338766Y505896D01*
X1334400D01*
G01X1353428Y513771D02*
X1360415D01*
X1359760Y515813D01*
X1358668Y516979D01*
X1357140Y517562D01*
X1355611Y517271D01*
X1354301Y516396D01*
X1353428Y514354D01*
X1352991Y512604D01*
Y510854D01*
X1353428Y509104D01*
X1354520Y507354D01*
X1355830Y506188D01*
X1357358Y505896D01*
X1358886Y506479D01*
X1360415Y508229D01*
G01X1370491Y505896D02*
Y517562D01*
G01Y514646D02*
X1371365Y516104D01*
X1372675Y517271D01*
X1374421Y517562D01*
X1375949Y517271D01*
X1377260Y516104D01*
X1377915Y514063D01*
Y505896D01*
G01X1391703D02*
X1390393Y506188D01*
X1389083Y507354D01*
X1388209Y509396D01*
X1387773Y511729D01*
X1388209Y514063D01*
X1389083Y516104D01*
X1390393Y517271D01*
X1391703Y517562D01*
X1393013Y517271D01*
X1394323Y516104D01*
X1395196Y514063D01*
X1395415Y511729D01*
X1395196Y509396D01*
X1394323Y507354D01*
X1393013Y506188D01*
X1391703Y505896D01*
G01X1409203Y523396D02*
Y505896D01*
G01X1406146Y517562D02*
X1412260D01*
G01X1423428Y513771D02*
X1430415D01*
X1429760Y515813D01*
X1428668Y516979D01*
X1427140Y517562D01*
X1425611Y517271D01*
X1424301Y516396D01*
X1423428Y514354D01*
X1422991Y512604D01*
Y510854D01*
X1423428Y509104D01*
X1424520Y507354D01*
X1425830Y506188D01*
X1427358Y505896D01*
X1428886Y506479D01*
X1430415Y508229D01*
G01X1440928Y507937D02*
X1442020Y506771D01*
X1443548Y505896D01*
X1444858D01*
X1446168Y506479D01*
X1447041Y507354D01*
X1447478Y508520D01*
X1447260Y510271D01*
X1446386Y511146D01*
X1442456Y512896D01*
X1441583Y514938D01*
X1442020Y516396D01*
X1442893Y517271D01*
X1444203Y517562D01*
X1445513Y517271D01*
X1446823Y516396D01*
G01X1479203Y523396D02*
Y505896D01*
G01X1476146Y517562D02*
X1482260D01*
G01X1492991Y505896D02*
Y523396D01*
G01Y514938D02*
X1494083Y516396D01*
X1495175Y517271D01*
X1496921Y517562D01*
X1498231Y517271D01*
X1499760Y516104D01*
X1500415Y514354D01*
Y505896D01*
G01X1518133D02*
Y517562D01*
G01Y515521D02*
X1517260Y516687D01*
X1515949Y517271D01*
X1514421Y517562D01*
X1512893Y516979D01*
X1511583Y515813D01*
X1510709Y514063D01*
X1510273Y511729D01*
X1510709Y509396D01*
X1511583Y507646D01*
X1512893Y506479D01*
X1514421Y505896D01*
X1515949Y506188D01*
X1517260Y507062D01*
X1518133Y508229D01*
G01X1531703Y523396D02*
Y505896D01*
G01X1528646Y517562D02*
X1534760D01*
G01X1566703Y523396D02*
Y505896D01*
G01X1563646Y517562D02*
X1569760D01*
G01X1580491Y505896D02*
Y523396D01*
G01Y514938D02*
X1581583Y516396D01*
X1582675Y517271D01*
X1584421Y517562D01*
X1585731Y517271D01*
X1587260Y516104D01*
X1587915Y514354D01*
Y505896D01*
G01X1601703Y517562D02*
Y505896D01*
G01Y522229D02*
X1601266Y522521D01*
Y523104D01*
X1601703Y523396D01*
X1602140Y523104D01*
Y522521D01*
X1601703Y522229D01*
G01X1615928Y507937D02*
X1617020Y506771D01*
X1618548Y505896D01*
X1619858D01*
X1621168Y506479D01*
X1622041Y507354D01*
X1622478Y508520D01*
X1622260Y510271D01*
X1621386Y511146D01*
X1617456Y512896D01*
X1616583Y514938D01*
X1617020Y516396D01*
X1617893Y517271D01*
X1619203Y517562D01*
X1620513Y517271D01*
X1621823Y516396D01*
G01X1651583Y523396D02*
X1656823D01*
G01X1654203D02*
Y505896D01*
G01X1651583D02*
X1656823D01*
G01X1665153D02*
Y517562D01*
G01Y514354D02*
X1665808Y515813D01*
X1666900Y516979D01*
X1668428Y517562D01*
X1669956Y516979D01*
X1671048Y515813D01*
X1671703Y514354D01*
Y505896D01*
G01Y514354D02*
X1672358Y515813D01*
X1673449Y516979D01*
X1674978Y517562D01*
X1676506Y516979D01*
X1677598Y515813D01*
X1678253Y514063D01*
Y505896D01*
G01X1685273Y500063D02*
Y517562D01*
G01Y514938D02*
X1686365Y516396D01*
X1687456Y517271D01*
X1689203Y517562D01*
X1690731Y517271D01*
X1692260Y515813D01*
X1692915Y513771D01*
X1693133Y511729D01*
X1692915Y509687D01*
X1692260Y507646D01*
X1690949Y506479D01*
X1689203Y505896D01*
X1687675Y506188D01*
X1686146Y507062D01*
X1685273Y508229D01*
G01X1703428Y513771D02*
X1710415D01*
X1709760Y515813D01*
X1708668Y516979D01*
X1707140Y517562D01*
X1705611Y517271D01*
X1704301Y516396D01*
X1703428Y514354D01*
X1702991Y512604D01*
Y510854D01*
X1703428Y509104D01*
X1704520Y507354D01*
X1705830Y506188D01*
X1707358Y505896D01*
X1708886Y506479D01*
X1710415Y508229D01*
G01X1728133Y523396D02*
Y505896D01*
G01Y508520D02*
X1727260Y507062D01*
X1725949Y506188D01*
X1724421Y505896D01*
X1722675Y506479D01*
X1721365Y507937D01*
X1720491Y509687D01*
X1720273Y511729D01*
X1720491Y513771D01*
X1721365Y515521D01*
X1722675Y516979D01*
X1724421Y517562D01*
X1725949Y517271D01*
X1727041Y516687D01*
X1728133Y515521D01*
G01X1745633Y505896D02*
Y517562D01*
G01Y515521D02*
X1744760Y516687D01*
X1743449Y517271D01*
X1741921Y517562D01*
X1740393Y516979D01*
X1739083Y515813D01*
X1738209Y514063D01*
X1737773Y511729D01*
X1738209Y509396D01*
X1739083Y507646D01*
X1740393Y506479D01*
X1741921Y505896D01*
X1743449Y506188D01*
X1744760Y507062D01*
X1745633Y508229D01*
G01X1755491Y505896D02*
Y517562D01*
G01Y514646D02*
X1756365Y516104D01*
X1757675Y517271D01*
X1759421Y517562D01*
X1760949Y517271D01*
X1762260Y516104D01*
X1762915Y514063D01*
Y505896D01*
G01X1780196Y516104D02*
X1778668Y517271D01*
X1777358Y517562D01*
X1775611Y516979D01*
X1774301Y515813D01*
X1773428Y513771D01*
X1773209Y511729D01*
X1773428Y509687D01*
X1774301Y507937D01*
X1775611Y506479D01*
X1777358Y505896D01*
X1778886Y506479D01*
X1780196Y507646D01*
G01X1790928Y513771D02*
X1797915D01*
X1797260Y515813D01*
X1796168Y516979D01*
X1794640Y517562D01*
X1793111Y517271D01*
X1791801Y516396D01*
X1790928Y514354D01*
X1790491Y512604D01*
Y510854D01*
X1790928Y509104D01*
X1792020Y507354D01*
X1793330Y506188D01*
X1794858Y505896D01*
X1796386Y506479D01*
X1797915Y508229D01*
M02*
